# T6G (Grand Teton) — schematic netlist excerpt (pin names and nets, part order shuffled) for the footprints in the layout excerpt that follows; sources: Cadence DE-HDL packaged netlist, KiCad conversion of 04192023_DAF0TMB3IC0_F0TG_MB_C_brd_V02_OCP.brd

R1271  Q_RES  0 5% CHIP  pkg 0402LF  page 357 : A = P12V_OCP_V3_2_ADC_ALERT_R ; B = OCP_V3_2_P3V3_P12V_ADC_R_ALERT
PR3830  Q_RES  10 1% CHIP  pkg 0402LF  page 140 : A = P12V_AUX ; B = P12V_OCP_VCC_2

(kicad_pcb
	(version 20260206)
	(generator "pcbnew")
	(generator_version "10.0")
	(general
		(thickness 1.6)
		(legacy_teardrops no)
	)
	(paper "A4")
	(title_block
		(title "04192023_DAF0TMB3IC0_F0TG_MB_C_brd_V02_OCP.brd")
		(comment 1 "Grand Teton / footprints 2565-2566 of 8354")
	)
	(layers
		(0 "F.Cu" signal "TOP")
		(4 "In1.Cu" signal "GND")
		(6 "In2.Cu" signal "IN1")
		(8 "In3.Cu" signal "GND1")
		(10 "In4.Cu" signal "IN2")
		(12 "In5.Cu" signal "GND2")
		(14 "In6.Cu" signal "IN3")
		(16 "In7.Cu" signal "GND3")
		(18 "In8.Cu" signal "VCC")
		(20 "In9.Cu" signal "VCC1")
		(22 "In10.Cu" signal "GND4")
		(24 "In11.Cu" signal "IN4")
		(26 "In12.Cu" signal "GND5")
		(28 "In13.Cu" signal "IN5")
		(30 "In14.Cu" signal "GND6")
		(32 "In15.Cu" signal "IN6")
		(34 "In16.Cu" signal "GND7")
		(2 "B.Cu" signal "BOTTOM")
		(9 "F.Adhes" user "F.Adhesive")
		(11 "B.Adhes" user "B.Adhesive")
		(13 "F.Paste" user "Package Geometry/Pastemask Top")
		(15 "B.Paste" user "Package Geometry/Pastemask Bottom")
		(5 "F.SilkS" user "Ref Des/Silkscreen Top")
		(7 "B.SilkS" user "Ref Des/Silkscreen Bottom")
		(1 "F.Mask" user "Board Geometry/Soldermask Top")
		(3 "B.Mask" user "Board Geometry/Soldermask Bottom")
		(17 "Dwgs.User" user "User.Drawings")
		(19 "Cmts.User" user "User.Comments")
		(21 "Eco1.User" user "User.Eco1")
		(23 "Eco2.User" user "User.Eco2")
		(25 "Edge.Cuts" user "Board Geometry/Outline")
		(27 "Margin" user)
		(31 "F.CrtYd" user "Package Geometry/Place Bound Top")
		(29 "B.CrtYd" user "Package Geometry/Place Bound Bottom")
		(35 "F.Fab" user "Ref Des/Assembly Top")
		(33 "B.Fab" user "Ref Des/Assembly Bottom")
	)
	(footprint ""
		(layer "F.Cu")
		(at 77.55001 -24.713946 -90)
		(property "Reference" "PR3830"
			(at 0 0 270)
			(layer "F.SilkS")
			(hide yes)
			(effects
				(font
					(size 1.27 1.27)
				)
			)
		)
		(property "Value" ""
			(at 0 0 270)
			(layer "F.Fab")
			(effects
				(font
					(size 1.27 1.27)
				)
			)
		)
		(duplicate_pad_numbers_are_jumpers no)
		(fp_line
			(start -0.7874 0.4064)
			(end -0.7874 -0.4064)
			(stroke
				(width 0.1524)
				(type default)
			)
			(layer "F.SilkS")
		)
		(fp_line
			(start 0.7874 0.4064)
			(end -0.7874 0.4064)
			(stroke
				(width 0.1524)
				(type default)
			)
			(layer "F.SilkS")
		)
		(fp_line
			(start -0.7874 -0.4064)
			(end 0.7874 -0.4064)
			(stroke
				(width 0.1524)
				(type default)
			)
			(layer "F.SilkS")
		)
		(fp_line
			(start 0.7874 -0.4064)
			(end 0.7874 0.4064)
			(stroke
				(width 0.1524)
				(type default)
			)
			(layer "F.SilkS")
		)
		(fp_line
			(start -0.67945 0.3048)
			(end -0.67945 -0.305054)
			(stroke
				(width 0.1)
				(type default)
			)
			(layer "F.Fab")
		)
		(fp_line
			(start -0.12065 0.3048)
			(end -0.67945 0.3048)
			(stroke
				(width 0.1)
				(type default)
			)
			(layer "F.Fab")
		)
		(fp_line
			(start 0.120396 0.3048)
			(end 0.120396 0.2794)
			(stroke
				(width 0.1)
				(type default)
			)
			(layer "F.Fab")
		)
		(fp_line
			(start 0.67945 0.3048)
			(end 0.120396 0.3048)
			(stroke
				(width 0.1)
				(type default)
			)
			(layer "F.Fab")
		)
		(fp_line
			(start -0.12065 0.2794)
			(end -0.12065 0.3048)
			(stroke
				(width 0.1)
				(type default)
			)
			(layer "F.Fab")
		)
		(fp_line
			(start 0.120396 0.2794)
			(end -0.12065 0.2794)
			(stroke
				(width 0.1)
				(type default)
			)
			(layer "F.Fab")
		)
		(fp_line
			(start -0.12065 -0.2794)
			(end 0.12065 -0.2794)
			(stroke
				(width 0.1)
				(type default)
			)
			(layer "F.Fab")
		)
		(fp_line
			(start 0.12065 -0.2794)
			(end 0.12065 -0.3048)
			(stroke
				(width 0.1)
				(type default)
			)
			(layer "F.Fab")
		)
		(fp_line
			(start 0.12065 -0.3048)
			(end 0.67945 -0.3048)
			(stroke
				(width 0.1)
				(type default)
			)
			(layer "F.Fab")
		)
		(fp_line
			(start 0.67945 -0.3048)
			(end 0.67945 0.3048)
			(stroke
				(width 0.1)
				(type default)
			)
			(layer "F.Fab")
		)
		(fp_line
			(start -0.67945 -0.305054)
			(end -0.12065 -0.305054)
			(stroke
				(width 0.1)
				(type default)
			)
			(layer "F.Fab")
		)
		(fp_line
			(start -0.12065 -0.305054)
			(end -0.12065 -0.2794)
			(stroke
				(width 0.1)
				(type default)
			)
			(layer "F.Fab")
		)
		(pad "1" smd circle
			(at -0.40005 0 270)
			(size 0 0)
			(layers "F.Cu" "F.Mask" "F.Paste")
			(net "P12V_AUX")
		)
		(pad "2" smd circle
			(at 0.40005 0 270)
			(size 0 0)
			(layers "F.Cu" "F.Mask" "F.Paste")
			(net "P12V_OCP_VCC_2")
		)
	)
	(footprint ""
		(layer "F.Cu")
		(at 19.241516 -37.894514 180)
		(property "Reference" "R1271"
			(at 0 0 180)
			(layer "F.SilkS")
			(hide yes)
			(effects
				(font
					(size 1.27 1.27)
				)
			)
		)
		(property "Value" ""
			(at 0 0 180)
			(layer "F.Fab")
			(effects
				(font
					(size 1.27 1.27)
				)
			)
		)
		(duplicate_pad_numbers_are_jumpers no)
		(fp_line
			(start 0.7874 0.4064)
			(end -0.7874 0.4064)
			(stroke
				(width 0.1524)
				(type default)
			)
			(layer "F.SilkS")
		)
		(fp_line
			(start 0.7874 -0.4064)
			(end 0.7874 0.4064)
			(stroke
				(width 0.1524)
				(type default)
			)
			(layer "F.SilkS")
		)
		(fp_line
			(start -0.7874 0.4064)
			(end -0.7874 -0.4064)
			(stroke
				(width 0.1524)
				(type default)
			)
			(layer "F.SilkS")
		)
		(fp_line
			(start -0.7874 -0.4064)
			(end 0.7874 -0.4064)
			(stroke
				(width 0.1524)
				(type default)
			)
			(layer "F.SilkS")
		)
		(fp_line
			(start 0.67945 0.3048)
			(end 0.120396 0.3048)
			(stroke
				(width 0.1)
				(type default)
			)
			(layer "F.Fab")
		)
		(fp_line
			(start 0.67945 -0.3048)
			(end 0.67945 0.3048)
			(stroke
				(width 0.1)
				(type default)
			)
			(layer "F.Fab")
		)
		(fp_line
			(start 0.12065 -0.2794)
			(end 0.12065 -0.3048)
			(stroke
				(width 0.1)
				(type default)
			)
			(layer "F.Fab")
		)
		(fp_line
			(start 0.12065 -0.3048)
			(end 0.67945 -0.3048)
			(stroke
				(width 0.1)
				(type default)
			)
			(layer "F.Fab")
		)
		(fp_line
			(start 0.120396 0.3048)
			(end 0.120396 0.2794)
			(stroke
				(width 0.1)
				(type default)
			)
			(layer "F.Fab")
		)
		(fp_line
			(start 0.120396 0.2794)
			(end -0.12065 0.2794)
			(stroke
				(width 0.1)
				(type default)
			)
			(layer "F.Fab")
		)
		(fp_line
			(start -0.12065 0.3048)
			(end -0.67945 0.3048)
			(stroke
				(width 0.1)
				(type default)
			)
			(layer "F.Fab")
		)
		(fp_line
			(start -0.12065 0.2794)
			(end -0.12065 0.3048)
			(stroke
				(width 0.1)
				(type default)
			)
			(layer "F.Fab")
		)
		(fp_line
			(start -0.12065 -0.2794)
			(end 0.12065 -0.2794)
			(stroke
				(width 0.1)
				(type default)
			)
			(layer "F.Fab")
		)
		(fp_line
			(start -0.12065 -0.305054)
			(end -0.12065 -0.2794)
			(stroke
				(width 0.1)
				(type default)
			)
			(layer "F.Fab")
		)
		(fp_line
			(start -0.67945 0.3048)
			(end -0.67945 -0.305054)
			(stroke
				(width 0.1)
				(type default)
			)
			(layer "F.Fab")
		)
		(fp_line
			(start -0.67945 -0.305054)
			(end -0.12065 -0.305054)
			(stroke
				(width 0.1)
				(type default)
			)
			(layer "F.Fab")
		)
		(pad "1" smd circle
			(at -0.40005 0 180)
			(size 0 0)
			(layers "F.Cu" "F.Mask" "F.Paste")
			(net "P12V_OCP_V3_2_ADC_ALERT_R")
		)
		(pad "2" smd circle
			(at 0.40005 0 180)
			(size 0 0)
			(layers "F.Cu" "F.Mask" "F.Paste")
			(net "OCP_V3_2_P3V3_P12V_ADC_R_ALERT")
		)
	)
)
